# SCM (Grand Teton) — schematic netlist excerpt (pin names and nets, part order shuffled) for the footprints in the layout excerpt that follows; sources: Cadence DE-HDL packaged netlist, KiCad conversion of 12092022_DA0F0TMDCD0_F0T_Management_Board_D_brd_V3_OCP.brd

U25  LCMXO3LF2100C5BG256C  LCMXO3LF-2100C-5BG256C IC  pkg BGA256_0-8_14X14  page 34
  VCC_A1  = PVCCA_AUX_PLD
  NC1  = NC
  PT11C  = BSM_PRSNT_R1_N
  PT10A  = RST_PLTRST_R1_N
  PT11A  = RST_RSMRST_N
  \pt12d||tdi\  = JTAG_SCM_PLD_TDI
  \pt16c||tck\  = JTAG_SCM_PLD_TCK
  \pt17b||pclkc0_1\  = IRQ_BMC_PCH_NMI_R_N
  \pt18c||scl||pclkt0_0\  = SMB_BMC_MM16_R3_SCL
  PT19B  = NC
  PT21A  = RST_EXTRST_R_N
  PT22B  = FM_ADR_COMPLETE
  \pt24c||initn\  = PU_FPGA_NSTATUS
  PT22D  = SGPIO_CLK_PLD_0
  PT24B  = FM_THERMTRIP_DLY_LVC1_R_N
  VCC_A16  = PVCCA_AUX_PLD
  PL1C  = NC
  GND_B2  = GND
  PT9C  = IRQ_BMC_CPU_NMI_R
  PT11D  = RST_PCA9548_SENSOR_N
  PT9B  = FM_TPM_PRSNT_1_R_N
  PT11B  = FM_JTAG_BMC_MUX_SEL_R2
  PT13A  = IRQ_UV_DETECT_N
  \pt16d||tms\  = JTAG_SCM_PLD_TMS
  PT19A  = IRQ_PCH_SCI_WHEA_N
  \pt20d||programn\  = PU_PT20D
  PT22A  = IRQ_OC_DETECT_N
  PT23B  = SGPIO_PLD_LD_0
  PT22C  = IRQ_OC_DETECT_EN_N
  PT24A  = SGPIO_PLD_DI_0
  GND_B15  = GND
  PR1D  = FM_PECI_SEL_N
  PL2C  = NC
  PL1D  = NC
  GND_C3  = GND
  PT9A  = FM_TPM_PRSNT_0_R_N
  PT10B  = PWRGD_PSU_AC_PWROK_PLD
  \pt12c||tdo\  = JTAG_SCM_PLD_TDO
  PT13B  = RST_BMC_RSTBTN_OUT_N
  \pt17a||pclkt0_1\  = CLK_25M_OSC_FPGA
  \pt18d||sda||pclkc0_0\  = SMB_BMC_MM16_R3_SDA
  \pt20c||jtagenb\  = JTAG_SCM_PLD_R_JTAGEN
  PT21B  = PWRGD_CPUPWRGD_LVC1
  PT23A  = SGPIO_PLD_DO_0
  \pt24d||done\  = PU_FPGA_CONFIG_DONE
  GND_C14  = GND
  PR1C  = VOL_SEN_ALERT_R
  PR2C  = SMB_BMC_ALERT3_R1_N
  \pl1b||l_gpllc_fb\  = NC
  PL2D  = NC
  \pl1a||l_gpllt_fb\  = NC
  GND_D4  = GND
  VCCIO0_D5  = VCCIO0
  PT12A  = FM_BMC_DBP_PRESENT_N
  PT13D  = FM_ME_BT_DONE
  PT17C  = FM_PCH_BMC_THERMTRIP_N
  PT18B  = NC
  PT20A  = NC
  PT21D  = IRQ_CPU1_VRHOT_N
  VCCIO0_D12  = VCCIO0
  GND_D13  = GND
  PR1A  = H_CPU0_MEMTRIP_LVC1_N
  PR2D  = SMB_BMC_ALERT4_R1_N
  PR2A  = H_CPU1_MEMTRIP_LVC1_N
  \pl3a||pclkt5_0\  = NC
  \pl2a||l_gpllt_in\  = NC
  \pl2b||l_gpllc_in\  = NC
  VCCIO5  = VCCIO5
  GND_E5  = GND
  PT13C  = BMC_CPLD_GPIO_2_R2
  PT12B  = PWRGD_PCH_PWROK
  PT16B  = FM_BIOS_POST_CMPLT_BMC_N
  PT17D  = H_CPU1_PROCHOT_LVC1_R_N
  PT20B  = FM_CPU_MSMI_CATERR_LVT3_PLD_N
  PT19D  = TP_PLD_19D
  GND_E12  = GND
  VCCIO1_E13  = VCCIO1
  PR2B  = IRQ_SGPIO_R_N
  PR1B  = FM_SPD_REMOTE_EN_R
  PR3A  = RST_SGPIO_RESET_R_N
  PL4B  = NC
  \pl3b||pclkc5_0\  = NC
  PL4A  = NC
  PL3C  = NC
  PL5C  = NC
  GND_F6  = GND
  PT16A  = FM_PCIE_M2_SSD0_PRSNT_N
  PT18A  = RST_SRST_PLD_BMC_R2_N
  PT19C  = NC
  PT21C  = IRQ_CPU0_VRHOT_N
  GND_F11  = GND
  PR4C  = TP_PLD_L3
  PR3C  = SMB_BMC_ALERT9_R1_N
  PR4A  = BMC_CPLD_GPIO_8_R2
  PR3B  = BMC_CPLD_GPIO_7_R2
  PR4B  = NC
  PL6A  = NC
  PL5A  = NC
  PL5B  = NC
  PL4D  = NC
  PL4C  = NC
  PL3D  = NC
  VCC_G7  = PVCCA_AUX_PLD
  VCCIO0_G8  = VCCIO0
  VCCIO0_G9  = VCCIO0
  VCC_G10  = PVCCA_AUX_PLD
  PR5C  = FM_SLPS3_GF_R_N
  PR3D  = SMB_BMC_ALERT10_R1_N
  PR4D  = RST_BMC_SELF_HW_R2
  PR5B  = NC
  PR5A  = NC
  PR6A  = BMC_CPLD_GPIO_12_R2
  PL7B  = NC
  PL6B  = NC
  PL7A  = NC
  PL6C  = NC
  PL9C  = NC
  PL5D  = NC
  VCCIO4_H7  = VCCIO4
  GND_H8  = GND
  GND_H9  = GND
  VCCIO1_H10  = VCCIO1
  PR9C  = RST_MB_STBY_R_N
  PR5D  = RST_ROT_CPU_R_N
  PR6C  = FM_ESPI_PLD_R_EN
  \pr7a||pclkt1_0\  = NC
  PR6B  = BMC_CPLD_GPIO_13_R2
  \pr7b||pclkc1_0\  = NC
  \pl7c||pclkt4_0\  = NC
  PL9A  = NC
  \pl7d||pclkc4_0\  = NC
  PL9D  = NC
  PL10C  = NC
  PL6D  = NC
  VCCIO4_J7  = VCCIO4
  GND_J8  = GND
  GND_J9  = GND
  VCCIO1_J10  = VCCIO1
  PR10C  = NC
  PR6D  = FM_THROTTLE_R_N
  PR9D  = FM_ADR_TRIGGER_N
  PR7D  = H_CPU0_PROCHOT_LVC1_R_N
  PR9A  = RST_BMC_HW_R
  PR7C  = FM_PMBUS_ALERT_EN
  PL9B  = NC
  PL10B  = NC
  PL10A  = NC
  PL11C  = NC
  PL12C  = NC
  PL10D  = NC
  VCC_K7  = PVCCA_AUX_PLD
  VCCIO2_K8  = VCCIO2
  VCCIO2_K9  = VCCIO2
  VCC_K10  = PVCCA_AUX_PLD
  PR12C  = FM_PCHHOT_R_N
  PR11D  = FM_BIOS_DEBUG_EN_N
  PR11C  = FM_BMC_READY_PLD_N
  PR10A  = FM_PWR_R_BTN
  PR10B  = PWRGD_SYS_PWROK_PLD
  PR9B  = NC
  PL11A  = NC
  \pl12a||pclkt3_0\  = NC
  PL11B  = NC
  PL12D  = NC
  PL11D  = NC
  GND_L6  = GND
  PB8D  = NC_FM_PFR_NO_SERVICE_ACT_N
  PB11D  = FM_PFR_DSW_PWROK_N
  PB12D  = FM_BMC_CPU_FBRK_OUT_R_N
  PB18D  = FM_UARTSW_MSB_R_N
  GND_L11  = GND
  PR10D  = FM_BMC_EN_DET_R
  PR12D  = FM_BMC_ONCTL_R_N
  PR11B  = SMB_BMC_ALERT12_N
  PR12A  = NC
  PR11A  = USB_OC0_REAR_R_N
  \pl12b||pclkc3_0\  = NC
  PL14A  = NC
  PL13A  = NC
  VCCIO3  = VCCIO3
  GND_M5  = GND
  PB11C  = BMC_MONITER
  PB9C  = CLK_GEN2_BMC_RC_OE_N
  PB16C  = PWRGD_P1V8_AUX_R1
  PB18C  = FM_UARTSW_LSB_R_N
  PB21C  = PU_FPGA_NCONFIG
  PB19D  = NC
  GND_M12  = GND
  VCCIO1_M13  = VCCIO1
  PR13A  = PWR_LED_CPLD
  PR13B  = PWRGD_P5V_AUX_R1
  PR12B  = NC
  PL13B  = NC
  PL13C  = NC
  PL14B  = NC
  GND_N4  = GND
  VCCIO2_N5  = VCCIO2
  PB8C  = FM_BMC_DEBUG_SW_R2_N
  PB9D  = IRQ_SML0_ALERT_R_N
  PB12C  = CLK_BUF1_GPU_FPGA_OE_R_N
  PB16D  = PWRGD_P3V3_RGM_R1
  PB19C  = NC
  PB21D  = NC
  VCCIO2_N12  = VCCIO2
  GND_N13  = GND
  PR14B  = PWRGD_P2V5_AUX_R1
  PR13C  = AC_PWR_BTN_R2_N
  PR14A  = PWRGD_P3V3_AUX_R1
  PL13D  = NC
  PL14D  = NC
  GND_P3  = GND
  PB3A  = FM_P12V_HSC_ENABLE_R2
  PB5B  = TP_PLD_C13
  \pb8a||mclk||cclk\  = FM_HDD_LED_N
  PB9B  = GPU_WP_HW_CTRL_R_N
  PB12A  = GPU_FPGA_RST_N
  \pb16b||pclkc2_1\  = PWRGD_P1V0_AUX_R1
  PB19A  = NC
  PB21B  = NC
  PB24A  = NC
  \pb25b||si||sispi\  = NC
  GND_P14  = GND
  PR14C  = NC
  PR13D  = NC
  PL14C  = NC
  GND_R2  = GND
  PB3D  = PWRGD_DSW_PWROK_R2
  PB6D  = FM_BMC_SUSACK_R2_N
  \pb5a||csspin\  = FM_DEBUG_PORT_R2_PRSNT_N
  PB6B  = FM_BMC_CRASHLOG_TRIG_R2_N
  PB9A  = GPU_NVS_PWR_BRAKE_R_N
  \pb11b||pclkc2_0\  = NC_FM_PFR_UPDATE_N
  PB18A  = NC
  PB19B  = NC
  PB22A  = NC
  \pb25a||sn\  = PU_PB25A
  PB22C  = NC
  PB25D  = SMB_BMC_MM16_R4_SDA
  GND_R15  = GND
  PR14D  = SMB_BMC_ALERT16_R2_N
  VCC_T1  = PVCCA_AUX_PLD
  PB3C  = FM_SOL_UART_CH_SEL_R2
  PB6C  = RST_WDTRST_PLD_R2_N
  PB3B  = NC
  PB6A  = IRQ_PCH_TPM_SPI_R2_N
  \pb8b||so||spiso\  = FM_PCH_BEEP_LED
  \pb11a||pclkt2_0\  = RST_PFR_OVR_RTC_R
  PB12B  = FM_JTAG_TCK_MUX_BMC_SEL
  \pb16a||pclkt2_1\  = PWRGD_P1V2_AUX_R1
  PB18B  = NC
  PB21A  = NC
  PB22B  = NC
  PB24B  = NC
  PB22D  = NC
  PB25C  = SMB_BMC_MM16_R4_SCL
  VCC_T16  = PVCCA_AUX_PLD

(kicad_pcb
	(version 20260206)
	(generator "pcbnew")
	(generator_version "10.0")
	(general
		(thickness 1.6)
		(legacy_teardrops no)
	)
	(paper "A4")
	(title_block
		(title "12092022_DA0F0TMDCD0_F0T_Management_Board_D_brd_V3_OCP.brd")
		(comment 1 "Grand Teton / footprint 162 of 1440 (U25), pads 141-188 of 256")
	)
	(layers
		(0 "F.Cu" signal "TOP")
		(4 "In1.Cu" signal "GND")
		(6 "In2.Cu" signal "IN1")
		(8 "In3.Cu" signal "GND1")
		(10 "In4.Cu" signal "IN2")
		(12 "In5.Cu" signal "VCC")
		(14 "In6.Cu" signal "VCC1")
		(16 "In7.Cu" signal "IN3")
		(18 "In8.Cu" signal "GND2")
		(20 "In9.Cu" signal "IN4")
		(22 "In10.Cu" signal "GND3")
		(2 "B.Cu" signal "BOTTOM")
		(9 "F.Adhes" user "F.Adhesive")
		(11 "B.Adhes" user "B.Adhesive")
		(13 "F.Paste" user "Package Geometry/Pastemask Top")
		(15 "B.Paste" user "Package Geometry/Pastemask Bottom")
		(5 "F.SilkS" user "Ref Des/Silkscreen Top")
		(7 "B.SilkS" user "Ref Des/Silkscreen Bottom")
		(1 "F.Mask" user "Board Geometry/Soldermask Top")
		(3 "B.Mask" user "Board Geometry/Soldermask Bottom")
		(17 "Dwgs.User" user "User.Drawings")
		(19 "Cmts.User" user "User.Comments")
		(21 "Eco1.User" user "User.Eco1")
		(23 "Eco2.User" user "User.Eco2")
		(25 "Edge.Cuts" user "Board Geometry/Outline")
		(27 "Margin" user)
		(31 "F.CrtYd" user "Package Geometry/Place Bound Top")
		(29 "B.CrtYd" user "Package Geometry/Place Bound Bottom")
		(35 "F.Fab" user "Ref Des/Assembly Top")
		(33 "B.Fab" user "Ref Des/Assembly Bottom")
	)
	(footprint ""
		(layer "F.Cu")
		(at 21.459444 -93.587062 180)
		(property "Reference" "U25"
			(at -10.595356 -8.218932 0)
			(unlocked yes)
			(layer "F.SilkS")
			(effects
				(font
					(size 0.7874 0.5842)
					(thickness 0.1524)
				)
				(justify left)
			)
		)
		(property "Value" ""
			(at 0 0 180)
			(layer "F.Fab")
			(effects
				(font
					(size 1.27 1.27)
				)
			)
		)
		(duplicate_pad_numbers_are_jumpers no)
		(pad "J13" smd circle
			(at 3.599942 0.40005 180)
			(size 0.4064 0.4064)
			(layers "F.Cu" "F.Mask" "F.Paste")
			(net "FM_ADR_TRIGGER_N")
		)
		(pad "J14" smd circle
			(at 4.400042 0.40005 180)
			(size 0.4064 0.4064)
			(layers "F.Cu" "F.Mask" "F.Paste")
			(net "H_CPU0_PROCHOT_LVC1_R_N")
		)
		(pad "J15" smd circle
			(at 5.199888 0.40005 180)
			(size 0.4064 0.4064)
			(layers "F.Cu" "F.Mask" "F.Paste")
			(net "RST_BMC_HW_R")
		)
		(pad "J16" smd circle
			(at 5.999988 0.40005 180)
			(size 0.4064 0.4064)
			(layers "F.Cu" "F.Mask" "F.Paste")
			(net "FM_PMBUS_ALERT_EN")
		)
		(pad "K1" smd circle
			(at -5.999988 1.199896 180)
			(size 0.4064 0.4064)
			(layers "F.Cu" "F.Mask" "F.Paste")
			(net "Net_293")
		)
		(pad "K2" smd circle
			(at -5.199888 1.199896 180)
			(size 0.4064 0.4064)
			(layers "F.Cu" "F.Mask" "F.Paste")
			(net "Net_281")
		)
		(pad "K3" smd circle
			(at -4.400042 1.199896 180)
			(size 0.4064 0.4064)
			(layers "F.Cu" "F.Mask" "F.Paste")
			(net "Net_280")
		)
		(pad "K4" smd circle
			(at -3.599942 1.199896 180)
			(size 0.4064 0.4064)
			(layers "F.Cu" "F.Mask" "F.Paste")
			(net "Net_266")
		)
		(pad "K5" smd circle
			(at -2.800096 1.199896 180)
			(size 0.4064 0.4064)
			(layers "F.Cu" "F.Mask" "F.Paste")
			(net "Net_270")
		)
		(pad "K6" smd circle
			(at -1.999996 1.199896 180)
			(size 0.4064 0.4064)
			(layers "F.Cu" "F.Mask" "F.Paste")
			(net "Net_283")
		)
		(pad "K7" smd circle
			(at -1.199896 1.199896 180)
			(size 0.4064 0.4064)
			(layers "F.Cu" "F.Mask" "F.Paste")
			(net "PVCCA_AUX_PLD")
		)
		(pad "K8" smd circle
			(at -0.40005 1.199896 180)
			(size 0.4064 0.4064)
			(layers "F.Cu" "F.Mask" "F.Paste")
			(net "VCCIO2")
		)
		(pad "K9" smd circle
			(at 0.40005 1.199896 180)
			(size 0.4064 0.4064)
			(layers "F.Cu" "F.Mask" "F.Paste")
			(net "VCCIO2")
		)
		(pad "K10" smd circle
			(at 1.199896 1.199896 180)
			(size 0.4064 0.4064)
			(layers "F.Cu" "F.Mask" "F.Paste")
			(net "PVCCA_AUX_PLD")
		)
		(pad "K11" smd circle
			(at 1.999996 1.199896 180)
			(size 0.4064 0.4064)
			(layers "F.Cu" "F.Mask" "F.Paste")
			(net "FM_PCHHOT_R_N")
		)
		(pad "K12" smd circle
			(at 2.800096 1.199896 180)
			(size 0.4064 0.4064)
			(layers "F.Cu" "F.Mask" "F.Paste")
			(net "FM_BIOS_DEBUG_EN_N")
		)
		(pad "K13" smd circle
			(at 3.599942 1.199896 180)
			(size 0.4064 0.4064)
			(layers "F.Cu" "F.Mask" "F.Paste")
			(net "FM_BMC_READY_PLD_N")
		)
		(pad "K14" smd circle
			(at 4.400042 1.199896 180)
			(size 0.4064 0.4064)
			(layers "F.Cu" "F.Mask" "F.Paste")
			(net "FM_PWR_R_BTN")
		)
		(pad "K15" smd circle
			(at 5.199888 1.199896 180)
			(size 0.4064 0.4064)
			(layers "F.Cu" "F.Mask" "F.Paste")
			(net "PWRGD_SYS_PWROK_PLD")
		)
		(pad "K16" smd circle
			(at 5.999988 1.199896 180)
			(size 0.4064 0.4064)
			(layers "F.Cu" "F.Mask" "F.Paste")
			(net "Net_247")
		)
		(pad "L1" smd circle
			(at -5.999988 1.999996 180)
			(size 0.4064 0.4064)
			(layers "F.Cu" "F.Mask" "F.Paste")
			(net "Net_264")
		)
		(pad "L2" smd circle
			(at -5.199888 1.999996 180)
			(size 0.4064 0.4064)
			(layers "F.Cu" "F.Mask" "F.Paste")
			(net "Net_268")
		)
		(pad "L3" smd circle
			(at -4.400042 1.999996 180)
			(size 0.4064 0.4064)
			(layers "F.Cu" "F.Mask" "F.Paste")
			(net "Net_265")
		)
		(pad "L4" smd circle
			(at -3.599942 1.999996 180)
			(size 0.4064 0.4064)
			(layers "F.Cu" "F.Mask" "F.Paste")
			(net "Net_271")
		)
		(pad "L5" smd circle
			(at -2.800096 1.999996 180)
			(size 0.4064 0.4064)
			(layers "F.Cu" "F.Mask" "F.Paste")
			(net "Net_267")
		)
		(pad "L6" smd circle
			(at -1.999996 1.999996 180)
			(size 0.4064 0.4064)
			(layers "F.Cu" "F.Mask" "F.Paste")
			(net "GND")
		)
		(pad "L7" smd circle
			(at -1.199896 1.999996 180)
			(size 0.4064 0.4064)
			(layers "F.Cu" "F.Mask" "F.Paste")
			(net "NC_FM_PFR_NO_SERVICE_ACT_N")
		)
		(pad "L8" smd circle
			(at -0.40005 1.999996 180)
			(size 0.4064 0.4064)
			(layers "F.Cu" "F.Mask" "F.Paste")
			(net "FM_PFR_DSW_PWROK_N")
		)
		(pad "L9" smd circle
			(at 0.40005 1.999996 180)
			(size 0.4064 0.4064)
			(layers "F.Cu" "F.Mask" "F.Paste")
			(net "FM_BMC_CPU_FBRK_OUT_R_N")
		)
		(pad "L10" smd circle
			(at 1.199896 1.999996 180)
			(size 0.4064 0.4064)
			(layers "F.Cu" "F.Mask" "F.Paste")
			(net "FM_UARTSW_MSB_R_N")
		)
		(pad "L11" smd circle
			(at 1.999996 1.999996 180)
			(size 0.4064 0.4064)
			(layers "F.Cu" "F.Mask" "F.Paste")
			(net "GND")
		)
		(pad "L12" smd circle
			(at 2.800096 1.999996 180)
			(size 0.4064 0.4064)
			(layers "F.Cu" "F.Mask" "F.Paste")
			(net "FM_BMC_EN_DET_R")
		)
		(pad "L13" smd circle
			(at 3.599942 1.999996 180)
			(size 0.4064 0.4064)
			(layers "F.Cu" "F.Mask" "F.Paste")
			(net "FM_BMC_ONCTL_R_N")
		)
		(pad "L14" smd circle
			(at 4.400042 1.999996 180)
			(size 0.4064 0.4064)
			(layers "F.Cu" "F.Mask" "F.Paste")
			(net "SMB_BMC_ALERT12_N")
		)
		(pad "L15" smd circle
			(at 5.199888 1.999996 180)
			(size 0.4064 0.4064)
			(layers "F.Cu" "F.Mask" "F.Paste")
			(net "Net_78")
		)
		(pad "L16" smd circle
			(at 5.999988 1.999996 180)
			(size 0.4064 0.4064)
			(layers "F.Cu" "F.Mask" "F.Paste")
			(net "USB_OC0_REAR_R_N")
		)
		(pad "M1" smd circle
			(at -5.999988 2.800096 180)
			(size 0.4064 0.4064)
			(layers "F.Cu" "F.Mask" "F.Paste")
			(net "Net_269")
		)
		(pad "M2" smd circle
			(at -5.199888 2.800096 180)
			(size 0.4064 0.4064)
			(layers "F.Cu" "F.Mask" "F.Paste")
			(net "Net_276")
		)
		(pad "M3" smd circle
			(at -4.400042 2.800096 180)
			(size 0.4064 0.4064)
			(layers "F.Cu" "F.Mask" "F.Paste")
			(net "Net_272")
		)
		(pad "M4" smd circle
			(at -3.599942 2.800096 180)
			(size 0.4064 0.4064)
			(layers "F.Cu" "F.Mask" "F.Paste")
			(net "VCCIO3")
		)
		(pad "M5" smd circle
			(at -2.800096 2.800096 180)
			(size 0.4064 0.4064)
			(layers "F.Cu" "F.Mask" "F.Paste")
			(net "GND")
		)
		(pad "M6" smd circle
			(at -1.999996 2.800096 180)
			(size 0.4064 0.4064)
			(layers "F.Cu" "F.Mask" "F.Paste")
			(net "BMC_MONITER")
		)
		(pad "M7" smd circle
			(at -1.199896 2.800096 180)
			(size 0.4064 0.4064)
			(layers "F.Cu" "F.Mask" "F.Paste")
			(net "CLK_GEN2_BMC_RC_OE_N")
		)
		(pad "M8" smd circle
			(at -0.40005 2.800096 180)
			(size 0.4064 0.4064)
			(layers "F.Cu" "F.Mask" "F.Paste")
			(net "PWRGD_P1V8_AUX_R1")
		)
		(pad "M9" smd circle
			(at 0.40005 2.800096 180)
			(size 0.4064 0.4064)
			(layers "F.Cu" "F.Mask" "F.Paste")
			(net "FM_UARTSW_LSB_R_N")
		)
		(pad "M10" smd circle
			(at 1.199896 2.800096 180)
			(size 0.4064 0.4064)
			(layers "F.Cu" "F.Mask" "F.Paste")
			(net "PU_FPGA_NCONFIG")
		)
		(pad "M11" smd circle
			(at 1.999996 2.800096 180)
			(size 0.4064 0.4064)
			(layers "F.Cu" "F.Mask" "F.Paste")
			(net "Net_253")
		)
		(pad "M12" smd circle
			(at 2.800096 2.800096 180)
			(size 0.4064 0.4064)
			(layers "F.Cu" "F.Mask" "F.Paste")
			(net "GND")
		)
	)
)
